(kicad_pcb
	(version 20241229)
	(generator "pcbnew")
	(generator_version "9.0")
	(general
		(thickness 1.294)
		(legacy_teardrops no)
	)
	(paper "A3")
	(title_block
		(title "Kintex 410T devboard")
		(date "2024-04-03")
		(rev "1.1.2")
		(comment 9 "footprints 527-532 of 975")
	)
	(layers
		(0 "F.Cu" mixed)
		(4 "In1.Cu" power)
		(6 "In2.Cu" power)
		(8 "In3.Cu" mixed)
		(10 "In4.Cu" power)
		(12 "In5.Cu" mixed)
		(14 "In6.Cu" power)
		(16 "In7.Cu" mixed)
		(18 "In8.Cu" power)
		(2 "B.Cu" mixed)
		(9 "F.Adhes" user "F.Adhesive")
		(11 "B.Adhes" user "B.Adhesive")
		(13 "F.Paste" user)
		(15 "B.Paste" user)
		(5 "F.SilkS" user "F.Silkscreen")
		(7 "B.SilkS" user "B.Silkscreen")
		(1 "F.Mask" user)
		(3 "B.Mask" user)
		(17 "Dwgs.User" user "User.Drawings")
		(19 "Cmts.User" user "User.Comments")
		(21 "Eco1.User" user "User.Eco1")
		(23 "Eco2.User" user "User.Eco2")
		(25 "Edge.Cuts" user)
		(27 "Margin" user)
		(31 "F.CrtYd" user "F.Courtyard")
		(29 "B.CrtYd" user "B.Courtyard")
		(35 "F.Fab" user)
		(33 "B.Fab" user)
	)
	(footprint "antmicro-footprints:R_0402_1005Metric"
		(layer "B.Cu")
		(at 164.0625 168.6 -90)
		(descr "Resistor SMD 0402")
		(tags "resistor SMD 0402")
		(property "Reference" "R299"
			(at 0.75 -0.3875 90)
			(layer "B.SilkS")
			(effects
				(font
					(size 0.7 0.7)
					(thickness 0.15)
				)
				(justify left bottom mirror)
			)
		)
		(property "Value" "R_0R_0402"
			(at 0 -1.4 90)
			(layer "B.Fab")
			(effects
				(font
					(size 0.7 0.7)
					(thickness 0.15)
				)
				(justify left bottom mirror)
			)
		)
		(property "Description" "SMD Chip Resistor, Jumper, 0 ohm, 100 mW, 0402 [1005 Metric], Thick Film, General Purpose"
			(at 0 0 270)
			(layer "F.Fab")
			(hide yes)
			(effects
				(font
					(size 1.27 1.27)
					(thickness 0.15)
				)
			)
		)
		(property "Author" "Antmicro"
			(at -4.5375 332.6625 0)
			(layer "B.Fab")
			(hide yes)
			(effects
				(font
					(size 1 1)
					(thickness 0.15)
				)
				(justify mirror)
			)
		)
		(property "Current" "1A"
			(at -4.5375 332.6625 0)
			(layer "B.Fab")
			(hide yes)
			(effects
				(font
					(size 1 1)
					(thickness 0.15)
				)
				(justify mirror)
			)
		)
		(property "DNP" "DNP"
			(at -4.5375 332.6625 0)
			(layer "B.Fab")
			(hide yes)
			(effects
				(font
					(size 1 1)
					(thickness 0.15)
				)
				(justify mirror)
			)
		)
		(property "License" "Apache-2.0"
			(at -4.5375 332.6625 0)
			(layer "B.Fab")
			(hide yes)
			(effects
				(font
					(size 1 1)
					(thickness 0.15)
				)
				(justify mirror)
			)
		)
		(property "MPN" "ERJ2GE0R00X"
			(at -4.5375 332.6625 0)
			(layer "B.Fab")
			(hide yes)
			(effects
				(font
					(size 1 1)
					(thickness 0.15)
				)
				(justify mirror)
			)
		)
		(property "Manufacturer" "Panasonic"
			(at -4.5375 332.6625 0)
			(layer "B.Fab")
			(hide yes)
			(effects
				(font
					(size 1 1)
					(thickness 0.15)
				)
				(justify mirror)
			)
		)
		(property "Tolerance" ""
			(at -4.5375 332.6625 0)
			(layer "B.Fab")
			(hide yes)
			(effects
				(font
					(size 1 1)
					(thickness 0.15)
				)
				(justify mirror)
			)
		)
		(property "Val" "0R"
			(at -4.5375 332.6625 0)
			(layer "B.Fab")
			(hide yes)
			(effects
				(font
					(size 1 1)
					(thickness 0.15)
				)
				(justify mirror)
			)
		)
		(property "dnp" ""
			(at -4.5375 332.6625 0)
			(layer "B.Fab")
			(hide yes)
			(effects
				(font
					(size 1 1)
					(thickness 0.15)
				)
				(justify mirror)
			)
		)
		(property "exclude_from_bom" ""
			(at -4.5375 332.6625 0)
			(layer "B.Fab")
			(hide yes)
			(effects
				(font
					(size 1 1)
					(thickness 0.15)
				)
				(justify mirror)
			)
		)
		(sheetname "DC-DC Converters")
		(sheetfile "dc-dc.kicad_sch")
		(attr smd exclude_from_bom)
		(fp_rect
			(start -0.925 0.47)
			(end 0.925 -0.47)
			(stroke
				(width 0.05)
				(type default)
			)
			(fill no)
			(layer "B.CrtYd")
		)
		(fp_rect
			(start -0.5 0.25)
			(end 0.5 -0.25)
			(stroke
				(width 0.15)
				(type solid)
			)
			(fill no)
			(layer "B.Fab")
		)
		(pad "1" smd roundrect
			(at -0.48 0 270)
			(size 0.59 0.64)
			(layers "B.Cu" "B.Mask" "B.Paste")
			(roundrect_rratio 0.25)
			(net 1223 "/DC-DC Converters/SENSE_1V8_N")
			(pintype "passive")
		)
		(pad "2" smd roundrect
			(at 0.48 0 270)
			(size 0.59 0.64)
			(layers "B.Cu" "B.Mask" "B.Paste")
			(roundrect_rratio 0.25)
			(net 960 "/DC-DC Converters/FB2")
			(pintype "passive")
		)
	)
	(footprint "antmicro-footprints:NetTie-2_SMD_Pad0.127mm"
		(layer "B.Cu")
		(at 207.860001 147.257 -90)
		(descr "Net tie, 2 pin, 0.127mm  SMD pads")
		(tags "net tie")
		(property "Reference" "NT29"
			(at -0.128 1.345 90)
			(layer "B.SilkS")
			(hide yes)
			(effects
				(font
					(size 0.7 0.7)
					(thickness 0.15)
				)
				(justify left bottom mirror)
			)
		)
		(property "Value" "Net-Tie_2"
			(at 0 -1.199 90)
			(layer "B.Fab")
			(effects
				(font
					(size 0.7 0.7)
					(thickness 0.15)
				)
				(justify left bottom mirror)
			)
		)
		(property "Description" "Net tie, 2 pins"
			(at 0 0 270)
			(layer "F.Fab")
			(hide yes)
			(effects
				(font
					(size 1.27 1.27)
					(thickness 0.15)
				)
			)
		)
		(property "Author" "Antmicro"
			(at 60.603001 355.117001 0)
			(layer "B.Fab")
			(hide yes)
			(effects
				(font
					(size 1 1)
					(thickness 0.15)
				)
				(justify mirror)
			)
		)
		(property "License" "Apache-2.0"
			(at 60.603001 355.117001 0)
			(layer "B.Fab")
			(hide yes)
			(effects
				(font
					(size 1 1)
					(thickness 0.15)
				)
				(justify mirror)
			)
		)
		(property "MPN" ""
			(at 60.603001 355.117001 0)
			(layer "B.Fab")
			(hide yes)
			(effects
				(font
					(size 1 1)
					(thickness 0.15)
				)
				(justify mirror)
			)
		)
		(property "Manufacturer" ""
			(at 60.603001 355.117001 0)
			(layer "B.Fab")
			(hide yes)
			(effects
				(font
					(size 1 1)
					(thickness 0.15)
				)
				(justify mirror)
			)
		)
		(sheetname "DC-DC Converters")
		(sheetfile "dc-dc.kicad_sch")
		(attr exclude_from_pos_files)
		(net_tie_pad_groups "1, 2")
		(fp_poly
			(pts
				(xy -0.0635 0.0635) (xy 0.0625 0.0635) (xy 0.0625 -0.0635) (xy -0.0635 -0.0635)
			)
			(stroke
				(width 0)
				(type solid)
			)
			(fill yes)
			(layer "B.Cu")
		)
		(pad "1" smd roundrect
			(at -0.127 0 90)
			(size 0.127 0.127)
			(layers "B.Cu")
			(roundrect_rratio 0.5)
			(chamfer_ratio 0)
			(chamfer top_left bottom_left)
			(net 1 "GND")
			(pinfunction "1")
			(pintype "passive")
		)
		(pad "2" smd roundrect
			(at 0.126 0 270)
			(size 0.127 0.127)
			(layers "B.Cu")
			(roundrect_rratio 0.5)
			(chamfer_ratio 0)
			(chamfer top_left bottom_left)
			(net 1217 "/DC-DC Converters/SENSE_3V3_1_N")
			(pinfunction "2")
			(pintype "passive")
		)
	)
	(footprint "antmicro-footprints:R_0402_1005Metric"
		(layer "B.Cu")
		(at 175.424999 147.999999 -90)
		(descr "Resistor SMD 0402")
		(tags "resistor SMD 0402")
		(property "Reference" "R40"
			(at 0.775001 -0.425001 90)
			(layer "B.SilkS")
			(effects
				(font
					(size 0.7 0.7)
					(thickness 0.15)
				)
				(justify left bottom mirror)
			)
		)
		(property "Value" "R_40R2_0402"
			(at 0 -1.4 90)
			(layer "B.Fab")
			(effects
				(font
					(size 0.7 0.7)
					(thickness 0.15)
				)
				(justify left bottom mirror)
			)
		)
		(property "Description" "SMD Chip Resistor, Ceramic, 40.2 ohm, ± 1%, 62.5 mW, 0402 [1005 Metric], Thick Film"
			(at 0 0 270)
			(layer "F.Fab")
			(hide yes)
			(effects
				(font
					(size 1.27 1.27)
					(thickness 0.15)
				)
			)
		)
		(property "Author" "Antmicro"
			(at 27.425 323.424998 0)
			(layer "B.Fab")
			(hide yes)
			(effects
				(font
					(size 1 1)
					(thickness 0.15)
				)
				(justify mirror)
			)
		)
		(property "License" "Apache-2.0"
			(at 27.425 323.424998 0)
			(layer "B.Fab")
			(hide yes)
			(effects
				(font
					(size 1 1)
					(thickness 0.15)
				)
				(justify mirror)
			)
		)
		(property "MPN" "CR0402-FX-40R2GLF"
			(at 27.425 323.424998 0)
			(layer "B.Fab")
			(hide yes)
			(effects
				(font
					(size 1 1)
					(thickness 0.15)
				)
				(justify mirror)
			)
		)
		(property "Manufacturer" "Bourns"
			(at 27.425 323.424998 0)
			(layer "B.Fab")
			(hide yes)
			(effects
				(font
					(size 1 1)
					(thickness 0.15)
				)
				(justify mirror)
			)
		)
		(property "Tolerance" "1%"
			(at 27.425 323.424998 0)
			(layer "B.Fab")
			(hide yes)
			(effects
				(font
					(size 1 1)
					(thickness 0.15)
				)
				(justify mirror)
			)
		)
		(property "Val" "40R2"
			(at 27.425 323.424998 0)
			(layer "B.Fab")
			(hide yes)
			(effects
				(font
					(size 1 1)
					(thickness 0.15)
				)
				(justify mirror)
			)
		)
		(sheetname "DRAM + SRAM")
		(sheetfile "ram.kicad_sch")
		(attr smd)
		(fp_rect
			(start -0.925 0.47)
			(end 0.925 -0.47)
			(stroke
				(width 0.05)
				(type default)
			)
			(fill no)
			(layer "B.CrtYd")
		)
		(fp_rect
			(start -0.5 0.25)
			(end 0.5 -0.25)
			(stroke
				(width 0.15)
				(type solid)
			)
			(fill no)
			(layer "B.Fab")
		)
		(pad "1" smd roundrect
			(at -0.48 0 270)
			(size 0.59 0.64)
			(layers "B.Cu" "B.Mask" "B.Paste")
			(roundrect_rratio 0.25)
			(net 557 "/DRAM + SRAM/DDR.DM")
			(pintype "passive")
		)
		(pad "2" smd roundrect
			(at 0.48 0 270)
			(size 0.59 0.64)
			(layers "B.Cu" "B.Mask" "B.Paste")
			(roundrect_rratio 0.25)
			(net 7 "+0V675_VTT")
			(pintype "passive")
		)
	)
	(footprint "antmicro-footprints:R_0402_1005Metric"
		(layer "B.Cu")
		(at 154.3125 169.2 -90)
		(descr "Resistor SMD 0402")
		(tags "resistor SMD 0402")
		(property "Reference" "R297"
			(at 0.7 -0.3875 90)
			(layer "B.SilkS")
			(effects
				(font
					(size 0.7 0.7)
					(thickness 0.15)
				)
				(justify left bottom mirror)
			)
		)
		(property "Value" "R_0R_0402"
			(at 0 -1.4 90)
			(layer "B.Fab")
			(effects
				(font
					(size 0.7 0.7)
					(thickness 0.15)
				)
				(justify left bottom mirror)
			)
		)
		(property "Description" "SMD Chip Resistor, Jumper, 0 ohm, 100 mW, 0402 [1005 Metric], Thick Film, General Purpose"
			(at 0 0 270)
			(layer "F.Fab")
			(hide yes)
			(effects
				(font
					(size 1.27 1.27)
					(thickness 0.15)
				)
			)
		)
		(property "Author" "Antmicro"
			(at -14.8875 323.5125 0)
			(layer "B.Fab")
			(hide yes)
			(effects
				(font
					(size 1 1)
					(thickness 0.15)
				)
				(justify mirror)
			)
		)
		(property "Current" "1A"
			(at -14.8875 323.5125 0)
			(layer "B.Fab")
			(hide yes)
			(effects
				(font
					(size 1 1)
					(thickness 0.15)
				)
				(justify mirror)
			)
		)
		(property "DNP" "DNP"
			(at -14.8875 323.5125 0)
			(layer "B.Fab")
			(hide yes)
			(effects
				(font
					(size 1 1)
					(thickness 0.15)
				)
				(justify mirror)
			)
		)
		(property "License" "Apache-2.0"
			(at -14.8875 323.5125 0)
			(layer "B.Fab")
			(hide yes)
			(effects
				(font
					(size 1 1)
					(thickness 0.15)
				)
				(justify mirror)
			)
		)
		(property "MPN" "ERJ2GE0R00X"
			(at -14.8875 323.5125 0)
			(layer "B.Fab")
			(hide yes)
			(effects
				(font
					(size 1 1)
					(thickness 0.15)
				)
				(justify mirror)
			)
		)
		(property "Manufacturer" "Panasonic"
			(at -14.8875 323.5125 0)
			(layer "B.Fab")
			(hide yes)
			(effects
				(font
					(size 1 1)
					(thickness 0.15)
				)
				(justify mirror)
			)
		)
		(property "Tolerance" ""
			(at -14.8875 323.5125 0)
			(layer "B.Fab")
			(hide yes)
			(effects
				(font
					(size 1 1)
					(thickness 0.15)
				)
				(justify mirror)
			)
		)
		(property "Val" "0R"
			(at -14.8875 323.5125 0)
			(layer "B.Fab")
			(hide yes)
			(effects
				(font
					(size 1 1)
					(thickness 0.15)
				)
				(justify mirror)
			)
		)
		(property "dnp" ""
			(at -14.8875 323.5125 0)
			(layer "B.Fab")
			(hide yes)
			(effects
				(font
					(size 1 1)
					(thickness 0.15)
				)
				(justify mirror)
			)
		)
		(property "exclude_from_bom" ""
			(at -14.8875 323.5125 0)
			(layer "B.Fab")
			(hide yes)
			(effects
				(font
					(size 1 1)
					(thickness 0.15)
				)
				(justify mirror)
			)
		)
		(sheetname "DC-DC Converters")
		(sheetfile "dc-dc.kicad_sch")
		(attr smd exclude_from_bom)
		(fp_rect
			(start -0.925 0.47)
			(end 0.925 -0.47)
			(stroke
				(width 0.05)
				(type default)
			)
			(fill no)
			(layer "B.CrtYd")
		)
		(fp_rect
			(start -0.5 0.25)
			(end 0.5 -0.25)
			(stroke
				(width 0.15)
				(type solid)
			)
			(fill no)
			(layer "B.Fab")
		)
		(pad "1" smd roundrect
			(at -0.48 0 270)
			(size 0.59 0.64)
			(layers "B.Cu" "B.Mask" "B.Paste")
			(roundrect_rratio 0.25)
			(net 1222 "/DC-DC Converters/SENSE_1V0_N")
			(pintype "passive")
		)
		(pad "2" smd roundrect
			(at 0.48 0 270)
			(size 0.59 0.64)
			(layers "B.Cu" "B.Mask" "B.Paste")
			(roundrect_rratio 0.25)
			(net 959 "/DC-DC Converters/FB1")
			(pintype "passive")
		)
	)
	(footprint "antmicro-footprints:C_0402_1005Metric"
		(layer "B.Cu")
		(at 170.1 149.425)
		(descr "Capacitor SMD 0402")
		(tags "capacitor SMD 0402")
		(property "Reference" "C185"
			(at 1.35 1.25 180)
			(layer "B.SilkS")
			(effects
				(font
					(size 0.7 0.7)
					(thickness 0.15)
				)
				(justify left bottom mirror)
			)
		)
		(property "Value" "C_100n_0402"
			(at 0 -1.169 180)
			(layer "B.Fab")
			(effects
				(font
					(size 0.7 0.7)
					(thickness 0.15)
				)
				(justify left bottom mirror)
			)
		)
		(property "Description" "SMD Multilayer Ceramic Capacitor, 0.1 µF, 50 V, 0402 [1005 Metric], ± 10%, X5R, GRM Series"
			(at 0 0 0)
			(layer "F.Fab")
			(hide yes)
			(effects
				(font
					(size 1.27 1.27)
					(thickness 0.15)
				)
			)
		)
		(property "Author" "Antmicro"
			(at 0 0 0)
			(layer "B.Fab")
			(hide yes)
			(effects
				(font
					(size 1 1)
					(thickness 0.15)
				)
				(justify mirror)
			)
		)
		(property "Dielectric" "X5R"
			(at 0 0 0)
			(layer "B.Fab")
			(hide yes)
			(effects
				(font
					(size 1 1)
					(thickness 0.15)
				)
				(justify mirror)
			)
		)
		(property "License" "Apache-2.0"
			(at 0 0 0)
			(layer "B.Fab")
			(hide yes)
			(effects
				(font
					(size 1 1)
					(thickness 0.15)
				)
				(justify mirror)
			)
		)
		(property "MPN" "GRM155R61H104KE14D"
			(at 0 0 0)
			(layer "B.Fab")
			(hide yes)
			(effects
				(font
					(size 1 1)
					(thickness 0.15)
				)
				(justify mirror)
			)
		)
		(property "Manufacturer" "Murata"
			(at 0 0 0)
			(layer "B.Fab")
			(hide yes)
			(effects
				(font
					(size 1 1)
					(thickness 0.15)
				)
				(justify mirror)
			)
		)
		(property "Val" "100n"
			(at 0 0 0)
			(layer "B.Fab")
			(hide yes)
			(effects
				(font
					(size 1 1)
					(thickness 0.15)
				)
				(justify mirror)
			)
		)
		(property "Voltage" "50V"
			(at 0 0 0)
			(layer "B.Fab")
			(hide yes)
			(effects
				(font
					(size 1 1)
					(thickness 0.15)
				)
				(justify mirror)
			)
		)
		(sheetname "DRAM + SRAM")
		(sheetfile "ram.kicad_sch")
		(attr smd)
		(fp_rect
			(start -0.925 0.47)
			(end 0.925 -0.47)
			(stroke
				(width 0.05)
				(type default)
			)
			(fill no)
			(layer "B.CrtYd")
		)
		(fp_line
			(start -0.494 -0.248)
			(end -0.494 0.25)
			(stroke
				(width 0.15)
				(type solid)
			)
			(layer "B.Fab")
		)
		(fp_line
			(start -0.494 0.25)
			(end 0.504 0.25)
			(stroke
				(width 0.15)
				(type solid)
			)
			(layer "B.Fab")
		)
		(fp_line
			(start 0.504 -0.248)
			(end -0.494 -0.248)
			(stroke
				(width 0.15)
				(type solid)
			)
			(layer "B.Fab")
		)
		(fp_line
			(start 0.504 0.25)
			(end 0.504 -0.248)
			(stroke
				(width 0.15)
				(type solid)
			)
			(layer "B.Fab")
		)
		(pad "1" smd roundrect
			(at -0.48 0)
			(size 0.59 0.64)
			(layers "B.Cu" "B.Mask" "B.Paste")
			(roundrect_rratio 0.25)
			(net 1 "GND")
			(pintype "passive")
		)
		(pad "2" smd roundrect
			(at 0.48 0)
			(size 0.59 0.64)
			(layers "B.Cu" "B.Mask" "B.Paste")
			(roundrect_rratio 0.25)
			(net 25 "+1V35")
			(pintype "passive")
		)
	)
	(footprint "antmicro-footprints:C_0201"
		(layer "B.Cu")
		(at 201.5 133.65 180)
		(descr "Capacitor SMD 0201")
		(tags "capacitor SMD 0201")
		(property "Reference" "C56"
			(at -26.925 28.225 0)
			(layer "B.SilkS")
			(effects
				(font
					(size 0.7 0.7)
					(thickness 0.15)
				)
				(justify left bottom mirror)
			)
		)
		(property "Value" "C_100n_0201"
			(at 0 -1.4 0)
			(layer "B.Fab")
			(effects
				(font
					(size 0.7 0.7)
					(thickness 0.15)
				)
				(justify left bottom mirror)
			)
		)
		(property "Description" "SMD Multilayer Ceramic Capacitor, 0.1 µF, 6.3 V, 0201 [0603 Metric], ± 10%, X6S, CC Series"
			(at 0 0 180)
			(layer "F.Fab")
			(hide yes)
			(effects
				(font
					(size 1.27 1.27)
					(thickness 0.15)
				)
			)
		)
		(property "Author" "Antmicro"
			(at 403 267.3 0)
			(layer "B.Fab")
			(hide yes)
			(effects
				(font
					(size 1 1)
					(thickness 0.15)
				)
				(justify mirror)
			)
		)
		(property "Dielectric" ""
			(at 403 267.3 0)
			(layer "B.Fab")
			(hide yes)
			(effects
				(font
					(size 1 1)
					(thickness 0.15)
				)
				(justify mirror)
			)
		)
		(property "License" "Apache-2.0"
			(at 403 267.3 0)
			(layer "B.Fab")
			(hide yes)
			(effects
				(font
					(size 1 1)
					(thickness 0.15)
				)
				(justify mirror)
			)
		)
		(property "MPN" "CC0201KRX6S5BB104"
			(at 403 267.3 0)
			(layer "B.Fab")
			(hide yes)
			(effects
				(font
					(size 1 1)
					(thickness 0.15)
				)
				(justify mirror)
			)
		)
		(property "Manufacturer" "YAGEO"
			(at 403 267.3 0)
			(layer "B.Fab")
			(hide yes)
			(effects
				(font
					(size 1 1)
					(thickness 0.15)
				)
				(justify mirror)
			)
		)
		(property "Val" "100n"
			(at 403 267.3 0)
			(layer "B.Fab")
			(hide yes)
			(effects
				(font
					(size 1 1)
					(thickness 0.15)
				)
				(justify mirror)
			)
		)
		(property "Voltage" ""
			(at 403 267.3 0)
			(layer "B.Fab")
			(hide yes)
			(effects
				(font
					(size 1 1)
					(thickness 0.15)
				)
				(justify mirror)
			)
		)
		(sheetname "FPGA supply")
		(sheetfile "fpga-supply.kicad_sch")
		(attr smd)
		(fp_rect
			(start -0.7 0.35)
			(end 0.7 -0.35)
			(stroke
				(width 0.05)
				(type default)
			)
			(fill no)
			(layer "B.CrtYd")
		)
		(fp_rect
			(start 0.3 -0.15)
			(end -0.301 0.149)
			(stroke
				(width 0.15)
				(type solid)
			)
			(fill no)
			(layer "B.Fab")
		)
		(pad "" smd roundrect
			(at -0.349 0.002 180)
			(size 0.318 0.36)
			(layers "B.Paste")
			(roundrect_rratio 0.25)
		)
		(pad "" smd roundrect
			(at 0.341 0.002 180)
			(size 0.318 0.36)
			(layers "B.Paste")
			(roundrect_rratio 0.25)
		)
		(pad "1" smd roundrect
			(at -0.321 0.002 180)
			(size 0.46 0.4)
			(layers "B.Cu" "B.Mask")
			(roundrect_rratio 0.25)
			(net 1 "GND")
			(pintype "passive")
		)
		(pad "2" smd roundrect
			(at 0.32 0.002 180)
			(size 0.46 0.4)
			(layers "B.Cu" "B.Mask")
			(roundrect_rratio 0.25)
			(net 650 "+1V0")
			(pintype "passive")
		)
	)
)
